(kicad_pcb
	(version 20260206)
	(generator "pcbnew")
	(generator_version "10.0")
	(general
		(thickness 1.6)
		(legacy_teardrops no)
	)
	(paper "A4")
	(title_block
		(title "panther-plus-userver — 13130-1b_20150205.brd")
		(comment 1 "Honey Badger (Wiwynn) / footprints 324-332 of 1509")
	)
	(layers
		(0 "F.Cu" signal "TOP")
		(4 "In1.Cu" signal "L2")
		(6 "In2.Cu" signal "L3")
		(8 "In3.Cu" signal "L4")
		(10 "In4.Cu" signal "L5")
		(12 "In5.Cu" signal "L6")
		(14 "In6.Cu" signal "L7")
		(16 "In7.Cu" signal "L8")
		(18 "In8.Cu" signal "L9")
		(20 "In9.Cu" signal "L10")
		(22 "In10.Cu" signal "L11")
		(2 "B.Cu" signal "BOTTOM")
		(9 "F.Adhes" user "F.Adhesive")
		(11 "B.Adhes" user "B.Adhesive")
		(13 "F.Paste" user "Package Geometry/Pastemask Top")
		(15 "B.Paste" user "Package Geometry/Pastemask Bottom")
		(5 "F.SilkS" user "Ref Des/Silkscreen Top")
		(7 "B.SilkS" user "Ref Des/Silkscreen Bottom")
		(1 "F.Mask" user "Board Geometry/Soldermask Top")
		(3 "B.Mask" user "Board Geometry/Soldermask Bottom")
		(17 "Dwgs.User" user "User.Drawings")
		(19 "Cmts.User" user "User.Comments")
		(21 "Eco1.User" user "User.Eco1")
		(23 "Eco2.User" user "User.Eco2")
		(25 "Edge.Cuts" user "Board Geometry/Outline")
		(27 "Margin" user)
		(31 "F.CrtYd" user "Package Geometry/Place Bound Top")
		(29 "B.CrtYd" user "Package Geometry/Place Bound Bottom")
		(35 "F.Fab" user "Ref Des/Assembly Top")
		(33 "B.Fab" user "Ref Des/Assembly Bottom")
	)
	(footprint ""
		(layer "F.Cu")
		(at 166.37 -48.006 -90)
		(property "Reference" "R212"
			(at 0 0 270)
			(layer "F.SilkS")
			(hide yes)
			(effects
				(font
					(size 1.27 1.27)
				)
			)
		)
		(property "Value" "0R2J-2-GP"
			(at 1.7907 -1.1176 270)
			(unlocked yes)
			(layer "F.Fab")
			(hide yes)
			(effects
				(font
					(size 1.016 1.016)
					(thickness 0.1524)
				)
			)
		)
		(property "Device Type" "R402H16"
			(at 1.7907 -2.6416 270)
			(unlocked yes)
			(layer "F.Fab")
			(hide yes)
			(effects
				(font
					(size 1.016 1.016)
					(thickness 0.1524)
				)
			)
		)
		(duplicate_pad_numbers_are_jumpers no)
		(fp_rect
			(start -0.381 0.8382)
			(end 0.381 -0.8382)
			(stroke
				(width 0)
				(type default)
			)
			(fill no)
			(layer "F.CrtYd")
		)
		(fp_rect
			(start -0.381 0.8382)
			(end 0.381 -0.8382)
			(stroke
				(width 0)
				(type default)
			)
			(fill no)
			(layer "F.Fab")
		)
		(pad "1" smd custom
			(at 0 -0.4318 270)
			(size 0.127 0.127)
			(layers "F.Cu" "F.Mask" "F.Paste")
			(net "XDP_SOC_CPU_TRST#")
			(options
				(clearance outline)
				(anchor circle)
			)
			(primitives
				(gr_poly
					(pts
						(arc
							(start -0.2032 -0.2794)
							(mid -0.239121 -0.264521)
							(end -0.254 -0.2286)
						)
						(arc
							(start -0.254 0.2286)
							(mid -0.239121 0.264521)
							(end -0.2032 0.2794)
						)
						(arc
							(start 0.2032 0.2794)
							(mid 0.239121 0.264521)
							(end 0.254 0.2286)
						)
						(arc
							(start 0.254 -0.2286)
							(mid 0.239121 -0.264521)
							(end 0.2032 -0.2794)
						)
					)
					(width 0)
					(fill yes)
				)
			)
		)
		(pad "2" smd custom
			(at 0 0.4318 270)
			(size 0.127 0.127)
			(layers "F.Cu" "F.Mask" "F.Paste")
			(net "XDP_SOC_CPU_TRST#_S")
			(options
				(clearance outline)
				(anchor circle)
			)
			(primitives
				(gr_poly
					(pts
						(arc
							(start -0.2032 -0.2794)
							(mid -0.239121 -0.264521)
							(end -0.254 -0.2286)
						)
						(arc
							(start -0.254 0.2286)
							(mid -0.239121 0.264521)
							(end -0.2032 0.2794)
						)
						(arc
							(start 0.2032 0.2794)
							(mid 0.239121 0.264521)
							(end 0.254 0.2286)
						)
						(arc
							(start 0.254 -0.2286)
							(mid 0.239121 -0.264521)
							(end 0.2032 -0.2794)
						)
					)
					(width 0)
					(fill yes)
				)
			)
		)
	)
	(footprint ""
		(layer "F.Cu")
		(at 151.2189 -49.0347 180)
		(property "Reference" "TP40"
			(at 0 0 180)
			(layer "F.SilkS")
			(hide yes)
			(effects
				(font
					(size 1.27 1.27)
				)
			)
		)
		(property "Value" "TPAD32-GP"
			(at 0 -3.166364 180)
			(unlocked yes)
			(layer "F.Fab")
			(hide yes)
			(effects
				(font
					(size 1.016 1.016)
					(thickness 0.1524)
				)
			)
		)
		(property "Device Type" "TPAD32"
			(at 0 -4.690618 180)
			(unlocked yes)
			(layer "F.Fab")
			(hide yes)
			(effects
				(font
					(size 1.016 1.016)
					(thickness 0.1524)
				)
			)
		)
		(duplicate_pad_numbers_are_jumpers no)
		(fp_poly
			(pts
				(arc
					(start -0.7112 0)
					(mid 0.7112 0)
					(end -0.7112 0)
				)
			)
			(stroke
				(width 0)
				(type default)
			)
			(fill no)
			(layer "F.CrtYd")
		)
		(fp_poly
			(pts
				(arc
					(start -0.7112 0)
					(mid 0.7112 0)
					(end -0.7112 0)
				)
			)
			(stroke
				(width 0)
				(type default)
			)
			(fill no)
			(layer "F.Fab")
		)
		(pad "1" smd circle
			(at 0 0 180)
			(size 0.8128 0.8128)
			(layers "F.Cu" "F.Mask" "F.Paste")
			(net "C_DATA0")
		)
	)
	(footprint ""
		(layer "F.Cu")
		(at 65.786 -12.954)
		(property "Reference" "R475"
			(at 0 0 0)
			(layer "F.SilkS")
			(hide yes)
			(effects
				(font
					(size 1.27 1.27)
				)
			)
		)
		(property "Value" "4K7R2F-GP"
			(at 1.7907 -1.1176 0)
			(unlocked yes)
			(layer "F.Fab")
			(hide yes)
			(effects
				(font
					(size 1.016 1.016)
					(thickness 0.1524)
				)
			)
		)
		(property "Device Type" "R402H16"
			(at 1.7907 -2.6416 0)
			(unlocked yes)
			(layer "F.Fab")
			(hide yes)
			(effects
				(font
					(size 1.016 1.016)
					(thickness 0.1524)
				)
			)
		)
		(duplicate_pad_numbers_are_jumpers no)
		(fp_rect
			(start -0.381 0.8382)
			(end 0.381 -0.8382)
			(stroke
				(width 0)
				(type default)
			)
			(fill no)
			(layer "F.CrtYd")
		)
		(fp_rect
			(start -0.381 0.8382)
			(end 0.381 -0.8382)
			(stroke
				(width 0)
				(type default)
			)
			(fill no)
			(layer "F.Fab")
		)
		(pad "1" smd custom
			(at 0 -0.4318)
			(size 0.127 0.127)
			(layers "F.Cu" "F.Mask" "F.Paste")
			(net "P3V3")
			(options
				(clearance outline)
				(anchor circle)
			)
			(primitives
				(gr_poly
					(pts
						(arc
							(start -0.2032 -0.2794)
							(mid -0.239121 -0.264521)
							(end -0.254 -0.2286)
						)
						(arc
							(start -0.254 0.2286)
							(mid -0.239121 0.264521)
							(end -0.2032 0.2794)
						)
						(arc
							(start 0.2032 0.2794)
							(mid 0.239121 0.264521)
							(end 0.254 0.2286)
						)
						(arc
							(start 0.254 -0.2286)
							(mid 0.239121 -0.264521)
							(end 0.2032 -0.2794)
						)
					)
					(width 0)
					(fill yes)
				)
			)
		)
		(pad "2" smd custom
			(at 0 0.4318)
			(size 0.127 0.127)
			(layers "F.Cu" "F.Mask" "F.Paste")
			(net "PMU_RESETBUTTON#")
			(options
				(clearance outline)
				(anchor circle)
			)
			(primitives
				(gr_poly
					(pts
						(arc
							(start -0.2032 -0.2794)
							(mid -0.239121 -0.264521)
							(end -0.254 -0.2286)
						)
						(arc
							(start -0.254 0.2286)
							(mid -0.239121 0.264521)
							(end -0.2032 0.2794)
						)
						(arc
							(start 0.2032 0.2794)
							(mid 0.239121 0.264521)
							(end 0.254 0.2286)
						)
						(arc
							(start 0.254 -0.2286)
							(mid 0.239121 -0.264521)
							(end 0.2032 -0.2794)
						)
					)
					(width 0)
					(fill yes)
				)
			)
		)
	)
	(footprint ""
		(layer "F.Cu")
		(at 71.247 -15.748 90)
		(property "Reference" "R461"
			(at 0 0 90)
			(layer "F.SilkS")
			(hide yes)
			(effects
				(font
					(size 1.27 1.27)
				)
			)
		)
		(property "Value" "4K7R2F-GP"
			(at 1.7907 -1.1176 90)
			(unlocked yes)
			(layer "F.Fab")
			(hide yes)
			(effects
				(font
					(size 1.016 1.016)
					(thickness 0.1524)
				)
			)
		)
		(property "Device Type" "R402H16"
			(at 1.7907 -2.6416 90)
			(unlocked yes)
			(layer "F.Fab")
			(hide yes)
			(effects
				(font
					(size 1.016 1.016)
					(thickness 0.1524)
				)
			)
		)
		(duplicate_pad_numbers_are_jumpers no)
		(fp_rect
			(start -0.381 0.8382)
			(end 0.381 -0.8382)
			(stroke
				(width 0)
				(type default)
			)
			(fill no)
			(layer "F.CrtYd")
		)
		(fp_rect
			(start -0.381 0.8382)
			(end 0.381 -0.8382)
			(stroke
				(width 0)
				(type default)
			)
			(fill no)
			(layer "F.Fab")
		)
		(pad "1" smd custom
			(at 0 -0.4318 90)
			(size 0.127 0.127)
			(layers "F.Cu" "F.Mask" "F.Paste")
			(net "P3V3_STBY")
			(options
				(clearance outline)
				(anchor circle)
			)
			(primitives
				(gr_poly
					(pts
						(arc
							(start -0.2032 -0.2794)
							(mid -0.239121 -0.264521)
							(end -0.254 -0.2286)
						)
						(arc
							(start -0.254 0.2286)
							(mid -0.239121 0.264521)
							(end -0.2032 0.2794)
						)
						(arc
							(start 0.2032 0.2794)
							(mid 0.239121 0.264521)
							(end 0.254 0.2286)
						)
						(arc
							(start 0.254 -0.2286)
							(mid 0.239121 -0.264521)
							(end 0.2032 -0.2794)
						)
					)
					(width 0)
					(fill yes)
				)
			)
		)
		(pad "2" smd custom
			(at 0 0.4318 90)
			(size 0.127 0.127)
			(layers "F.Cu" "F.Mask" "F.Paste")
			(net "BMC_I2C_ALERT#")
			(options
				(clearance outline)
				(anchor circle)
			)
			(primitives
				(gr_poly
					(pts
						(arc
							(start -0.2032 -0.2794)
							(mid -0.239121 -0.264521)
							(end -0.254 -0.2286)
						)
						(arc
							(start -0.254 0.2286)
							(mid -0.239121 0.264521)
							(end -0.2032 0.2794)
						)
						(arc
							(start 0.2032 0.2794)
							(mid 0.239121 0.264521)
							(end 0.254 0.2286)
						)
						(arc
							(start 0.254 -0.2286)
							(mid 0.239121 -0.264521)
							(end 0.2032 -0.2794)
						)
					)
					(width 0)
					(fill yes)
				)
			)
		)
	)
	(footprint ""
		(layer "F.Cu")
		(at 46.101 -18.415 90)
		(property "Reference" "R341"
			(at 0 0 90)
			(layer "F.SilkS")
			(hide yes)
			(effects
				(font
					(size 1.27 1.27)
				)
			)
		)
		(property "Value" "4K7R2F-GP"
			(at 0.064008 -3.993896 90)
			(unlocked yes)
			(layer "F.Fab")
			(hide yes)
			(effects
				(font
					(size 1.016 1.016)
					(thickness 0.1524)
				)
			)
		)
		(property "Device Type" "R402H16"
			(at 0.064008 -5.517896 90)
			(unlocked yes)
			(layer "F.Fab")
			(hide yes)
			(effects
				(font
					(size 1.016 1.016)
					(thickness 0.1524)
				)
			)
		)
		(duplicate_pad_numbers_are_jumpers no)
		(fp_rect
			(start -0.381 0.8382)
			(end 0.381 -0.8382)
			(stroke
				(width 0)
				(type default)
			)
			(fill no)
			(layer "F.CrtYd")
		)
		(fp_rect
			(start -0.381 0.8382)
			(end 0.381 -0.8382)
			(stroke
				(width 0)
				(type default)
			)
			(fill no)
			(layer "F.Fab")
		)
		(pad "1" smd custom
			(at 0 -0.4318 90)
			(size 0.127 0.127)
			(layers "F.Cu" "F.Mask" "F.Paste")
			(net "CLKBUFF_OE1#")
			(options
				(clearance outline)
				(anchor circle)
			)
			(primitives
				(gr_poly
					(pts
						(arc
							(start -0.2032 -0.2794)
							(mid -0.239121 -0.264521)
							(end -0.254 -0.2286)
						)
						(arc
							(start -0.254 0.2286)
							(mid -0.239121 0.264521)
							(end -0.2032 0.2794)
						)
						(arc
							(start 0.2032 0.2794)
							(mid 0.239121 0.264521)
							(end 0.254 0.2286)
						)
						(arc
							(start 0.254 -0.2286)
							(mid 0.239121 -0.264521)
							(end 0.2032 -0.2794)
						)
					)
					(width 0)
					(fill yes)
				)
			)
		)
		(pad "2" smd custom
			(at 0 0.4318 90)
			(size 0.127 0.127)
			(layers "F.Cu" "F.Mask" "F.Paste")
			(net "GND")
			(options
				(clearance outline)
				(anchor circle)
			)
			(primitives
				(gr_poly
					(pts
						(arc
							(start -0.2032 -0.2794)
							(mid -0.239121 -0.264521)
							(end -0.254 -0.2286)
						)
						(arc
							(start -0.254 0.2286)
							(mid -0.239121 0.264521)
							(end -0.2032 0.2794)
						)
						(arc
							(start 0.2032 0.2794)
							(mid 0.239121 0.264521)
							(end 0.254 0.2286)
						)
						(arc
							(start 0.254 -0.2286)
							(mid 0.239121 -0.264521)
							(end 0.2032 -0.2794)
						)
					)
					(width 0)
					(fill yes)
				)
			)
		)
	)
	(footprint ""
		(layer "F.Cu")
		(at 15.3924 -52.578)
		(property "Reference" "PC57"
			(at 0 0 0)
			(layer "F.SilkS")
			(hide yes)
			(effects
				(font
					(size 1.27 1.27)
				)
			)
		)
		(property "Value" "SC1KP50V2KX-1GP"
			(at 1.8923 -1.2065 0)
			(unlocked yes)
			(layer "F.Fab")
			(hide yes)
			(effects
				(font
					(size 1.016 1.016)
					(thickness 0.1524)
				)
			)
		)
		(property "Device Type" "C402H22"
			(at 1.8923 -2.7305 0)
			(unlocked yes)
			(layer "F.Fab")
			(hide yes)
			(effects
				(font
					(size 1.016 1.016)
					(thickness 0.1524)
				)
			)
		)
		(duplicate_pad_numbers_are_jumpers no)
		(fp_rect
			(start -0.381 0.7366)
			(end 0.381 -0.7366)
			(stroke
				(width 0)
				(type default)
			)
			(fill no)
			(layer "F.CrtYd")
		)
		(fp_rect
			(start -0.381 0.7366)
			(end 0.381 -0.7366)
			(stroke
				(width 0)
				(type default)
			)
			(fill no)
			(layer "F.Fab")
		)
		(pad "1" smd custom
			(at 0 -0.4572)
			(size 0.1143 0.1143)
			(layers "F.Cu" "F.Mask" "F.Paste")
			(net "VR_PVCCP_VW")
			(options
				(clearance outline)
				(anchor circle)
			)
			(primitives
				(gr_poly
					(pts
						(arc
							(start -0.254 -0.1778)
							(mid -0.239121 -0.213721)
							(end -0.2032 -0.2286)
						)
						(arc
							(start 0.2032 -0.2286)
							(mid 0.239121 -0.213721)
							(end 0.254 -0.1778)
						)
						(arc
							(start 0.254 0.1778)
							(mid 0.239121 0.213721)
							(end 0.2032 0.2286)
						)
						(arc
							(start -0.2032 0.2286)
							(mid -0.239121 0.213721)
							(end -0.254 0.1778)
						)
					)
					(width 0)
					(fill yes)
				)
			)
		)
		(pad "2" smd custom
			(at 0 0.4572)
			(size 0.1143 0.1143)
			(layers "F.Cu" "F.Mask" "F.Paste")
			(net "VR_PVCCP_COMP")
			(options
				(clearance outline)
				(anchor circle)
			)
			(primitives
				(gr_poly
					(pts
						(arc
							(start -0.254 -0.1778)
							(mid -0.239121 -0.213721)
							(end -0.2032 -0.2286)
						)
						(arc
							(start 0.2032 -0.2286)
							(mid 0.239121 -0.213721)
							(end 0.254 -0.1778)
						)
						(arc
							(start 0.254 0.1778)
							(mid 0.239121 0.213721)
							(end 0.2032 0.2286)
						)
						(arc
							(start -0.2032 0.2286)
							(mid -0.239121 0.213721)
							(end -0.254 0.1778)
						)
					)
					(width 0)
					(fill yes)
				)
			)
		)
	)
	(footprint ""
		(layer "F.Cu")
		(at 111.506 -19.177 -90)
		(property "Reference" "R168"
			(at 0 0 270)
			(layer "F.SilkS")
			(hide yes)
			(effects
				(font
					(size 1.27 1.27)
				)
			)
		)
		(property "Value" "100R3F-1-GP"
			(at -0.0254 -2.5146 270)
			(unlocked yes)
			(layer "F.Fab")
			(hide yes)
			(effects
				(font
					(size 1.016 1.016)
					(thickness 0.1524)
				)
			)
		)
		(property "Device Type" "R603H22"
			(at -0.0254 -4.0386 270)
			(unlocked yes)
			(layer "F.Fab")
			(hide yes)
			(effects
				(font
					(size 1.016 1.016)
					(thickness 0.1524)
				)
			)
		)
		(duplicate_pad_numbers_are_jumpers no)
		(fp_line
			(start -0.2032 0)
			(end -0.4191 0)
			(stroke
				(width 0.2032)
				(type default)
			)
			(layer "F.SilkS")
		)
		(fp_line
			(start 0.4318 0)
			(end 0.2032 0)
			(stroke
				(width 0.2032)
				(type default)
			)
			(layer "F.SilkS")
		)
		(fp_rect
			(start -0.635 1.1811)
			(end 0.635 -1.1811)
			(stroke
				(width 0)
				(type default)
			)
			(fill no)
			(layer "F.CrtYd")
		)
		(fp_rect
			(start -0.635 1.1811)
			(end 0.635 -1.1811)
			(stroke
				(width 0)
				(type default)
			)
			(fill no)
			(layer "F.Fab")
		)
		(pad "1" smd custom
			(at 0 -0.6604 270)
			(size 0.19685 0.19685)
			(layers "F.Cu" "F.Mask" "F.Paste")
			(net "M_B_MON1_P")
			(options
				(clearance outline)
				(anchor circle)
			)
			(primitives
				(gr_poly
					(pts
						(arc
							(start 0.508 -0.2921)
							(mid 0.478242 -0.363942)
							(end 0.4064 -0.3937)
						)
						(arc
							(start -0.4064 -0.3937)
							(mid -0.478242 -0.363942)
							(end -0.508 -0.2921)
						)
						(arc
							(start -0.508 0.2921)
							(mid -0.478242 0.363942)
							(end -0.4064 0.3937)
						)
						(arc
							(start 0.4064 0.3937)
							(mid 0.478242 0.363942)
							(end 0.508 0.2921)
						)
					)
					(width 0)
					(fill yes)
				)
			)
		)
		(pad "2" smd custom
			(at 0 0.6604 270)
			(size 0.19685 0.19685)
			(layers "F.Cu" "F.Mask" "F.Paste")
			(net "M_B_MON1_N")
			(options
				(clearance outline)
				(anchor circle)
			)
			(primitives
				(gr_poly
					(pts
						(arc
							(start 0.508 -0.2921)
							(mid 0.478242 -0.363942)
							(end 0.4064 -0.3937)
						)
						(arc
							(start -0.4064 -0.3937)
							(mid -0.478242 -0.363942)
							(end -0.508 -0.2921)
						)
						(arc
							(start -0.508 0.2921)
							(mid -0.478242 0.363942)
							(end -0.4064 0.3937)
						)
						(arc
							(start 0.4064 0.3937)
							(mid 0.478242 0.363942)
							(end 0.508 0.2921)
						)
					)
					(width 0)
					(fill yes)
				)
			)
		)
	)
	(footprint ""
		(layer "F.Cu")
		(at 64.77 -56.642)
		(property "Reference" "PR78"
			(at 0 0 0)
			(layer "F.SilkS")
			(hide yes)
			(effects
				(font
					(size 1.27 1.27)
				)
			)
		)
		(property "Value" "120R3F-L-GP"
			(at -0.0254 -2.5146 0)
			(unlocked yes)
			(layer "F.Fab")
			(hide yes)
			(effects
				(font
					(size 1.016 1.016)
					(thickness 0.1524)
				)
			)
		)
		(property "Device Type" "R603H22"
			(at -0.0254 -4.0386 0)
			(unlocked yes)
			(layer "F.Fab")
			(hide yes)
			(effects
				(font
					(size 1.016 1.016)
					(thickness 0.1524)
				)
			)
		)
		(duplicate_pad_numbers_are_jumpers no)
		(fp_line
			(start -0.2032 0)
			(end -0.4191 0)
			(stroke
				(width 0.2032)
				(type default)
			)
			(layer "F.SilkS")
		)
		(fp_line
			(start 0.4318 0)
			(end 0.2032 0)
			(stroke
				(width 0.2032)
				(type default)
			)
			(layer "F.SilkS")
		)
		(fp_rect
			(start -0.635 1.1811)
			(end 0.635 -1.1811)
			(stroke
				(width 0)
				(type default)
			)
			(fill no)
			(layer "F.CrtYd")
		)
		(fp_rect
			(start -0.635 1.1811)
			(end 0.635 -1.1811)
			(stroke
				(width 0)
				(type default)
			)
			(fill no)
			(layer "F.Fab")
		)
		(pad "1" smd custom
			(at 0 -0.6604)
			(size 0.19685 0.19685)
			(layers "F.Cu" "F.Mask" "F.Paste")
			(net "PVCCP")
			(options
				(clearance outline)
				(anchor circle)
			)
			(primitives
				(gr_poly
					(pts
						(arc
							(start 0.508 -0.2921)
							(mid 0.478242 -0.363942)
							(end 0.4064 -0.3937)
						)
						(arc
							(start -0.4064 -0.3937)
							(mid -0.478242 -0.363942)
							(end -0.508 -0.2921)
						)
						(arc
							(start -0.508 0.2921)
							(mid -0.478242 0.363942)
							(end -0.4064 0.3937)
						)
						(arc
							(start 0.4064 0.3937)
							(mid 0.478242 0.363942)
							(end 0.508 0.2921)
						)
					)
					(width 0)
					(fill yes)
				)
			)
		)
		(pad "2" smd custom
			(at 0 0.6604)
			(size 0.19685 0.19685)
			(layers "F.Cu" "F.Mask" "F.Paste")
			(net "GND")
			(options
				(clearance outline)
				(anchor circle)
			)
			(primitives
				(gr_poly
					(pts
						(arc
							(start 0.508 -0.2921)
							(mid 0.478242 -0.363942)
							(end 0.4064 -0.3937)
						)
						(arc
							(start -0.4064 -0.3937)
							(mid -0.478242 -0.363942)
							(end -0.508 -0.2921)
						)
						(arc
							(start -0.508 0.2921)
							(mid -0.478242 0.363942)
							(end -0.4064 0.3937)
						)
						(arc
							(start 0.4064 0.3937)
							(mid 0.478242 0.363942)
							(end 0.508 0.2921)
						)
					)
					(width 0)
					(fill yes)
				)
			)
		)
	)
	(footprint ""
		(layer "F.Cu")
		(at 40.767 -65.278 90)
		(property "Reference" "PL1"
			(at 0 0 90)
			(layer "F.SilkS")
			(hide yes)
			(effects
				(font
					(size 1.27 1.27)
				)
			)
		)
		(property "Value" "COIL-1UH-50-GP"
			(at -5.289296 -6.964934 90)
			(unlocked yes)
			(layer "F.Fab")
			(hide yes)
			(effects
				(font
					(size 1.016 1.016)
					(thickness 0.1524)
				)
			)
		)
		(property "Device Type" "L7467-1432-1H119"
			(at -5.289296 -8.488934 90)
			(unlocked yes)
			(layer "F.Fab")
			(hide yes)
			(effects
				(font
					(size 1.016 1.016)
					(thickness 0.1524)
				)
			)
		)
		(duplicate_pad_numbers_are_jumpers no)
		(fp_rect
			(start -3.6068 4.2164)
			(end 3.6068 -4.2164)
			(stroke
				(width 0)
				(type default)
			)
			(fill no)
			(layer "F.CrtYd")
		)
		(fp_rect
			(start -3.6068 4.2164)
			(end 3.6068 -4.2164)
			(stroke
				(width 0)
				(type default)
			)
			(fill no)
			(layer "F.Fab")
		)
		(pad "1" smd rect
			(at 0 -3.06197 90)
			(size 3.4544 2.032)
			(layers "F.Cu" "F.Mask" "F.Paste")
			(net "VR_PVNN_PHASE")
		)
		(pad "2" smd rect
			(at 0 3.06197 90)
			(size 3.4544 2.032)
			(layers "F.Cu" "F.Mask" "F.Paste")
			(net "PVNN")
		)
	)
)
